# S9S_MB_2U (Grand Teton) — schematic netlist excerpt (pin names and nets, part order shuffled) for the footprints in the layout excerpt that follows; sources: Cadence DE-HDL packaged netlist, KiCad conversion of 03242023_DA0F0TMBIJ0_F0T_Motherboard_J_brd_V01_OCP.brd

R608  Q_RES  10K 1% CHIP  pkg 0402LF  page 199 : A = FM_ESPI_FLASH_MODE ; B = GND
C849  Q_CAP_DIFFBUS  DIFF BUS_0.22UF 6.3V 20% X6S  pkg C0201  page 174 : \1\ = P5E_CPU0_PE1_TX_C_DP<10> ; \2\ = P5E_CPU0_PE1_TX_DP<10>
R4777  Q_RES  5.11K 1% EMPTY  pkg 0402LF  page 307 : A = P12V_AUX_UV_TRIGGER ; B = GND

(kicad_pcb
	(version 20260206)
	(generator "pcbnew")
	(generator_version "10.0")
	(general
		(thickness 1.6)
		(legacy_teardrops no)
	)
	(paper "A4")
	(title_block
		(title "03242023_DA0F0TMBIJ0_F0T_Motherboard_J_brd_V01_OCP.brd")
		(comment 1 "Grand Teton / footprints 1222-1224 of 6105")
	)
	(layers
		(0 "F.Cu" signal "TOP")
		(4 "In1.Cu" signal "GND")
		(6 "In2.Cu" signal "IN1")
		(8 "In3.Cu" signal "GND1")
		(10 "In4.Cu" signal "IN2")
		(12 "In5.Cu" signal "GND2")
		(14 "In6.Cu" signal "IN3")
		(16 "In7.Cu" signal "GND3")
		(18 "In8.Cu" signal "VCC")
		(20 "In9.Cu" signal "VCC1")
		(22 "In10.Cu" signal "GND4")
		(24 "In11.Cu" signal "IN4")
		(26 "In12.Cu" signal "GND5")
		(28 "In13.Cu" signal "IN5")
		(30 "In14.Cu" signal "GND6")
		(32 "In15.Cu" signal "IN6")
		(34 "In16.Cu" signal "GND7")
		(2 "B.Cu" signal "BOTTOM")
		(9 "F.Adhes" user "F.Adhesive")
		(11 "B.Adhes" user "B.Adhesive")
		(13 "F.Paste" user "Package Geometry/Pastemask Top")
		(15 "B.Paste" user "Package Geometry/Pastemask Bottom")
		(5 "F.SilkS" user "Ref Des/Silkscreen Top")
		(7 "B.SilkS" user "Ref Des/Silkscreen Bottom")
		(1 "F.Mask" user "Board Geometry/Soldermask Top")
		(3 "B.Mask" user "Board Geometry/Soldermask Bottom")
		(17 "Dwgs.User" user "User.Drawings")
		(19 "Cmts.User" user "User.Comments")
		(21 "Eco1.User" user "User.Eco1")
		(23 "Eco2.User" user "User.Eco2")
		(25 "Edge.Cuts" user "Board Geometry/Outline")
		(27 "Margin" user)
		(31 "F.CrtYd" user "Package Geometry/Place Bound Top")
		(29 "B.CrtYd" user "Package Geometry/Place Bound Bottom")
		(35 "F.Fab" user "Ref Des/Assembly Top")
		(33 "B.Fab" user "Ref Des/Assembly Bottom")
	)
	(footprint ""
		(layer "F.Cu")
		(at 307.363622 -44.948348 180)
		(property "Reference" "R608"
			(at 0 0 180)
			(layer "F.SilkS")
			(hide yes)
			(effects
				(font
					(size 1.27 1.27)
				)
			)
		)
		(property "Value" ""
			(at 0 0 180)
			(layer "F.Fab")
			(effects
				(font
					(size 1.27 1.27)
				)
			)
		)
		(duplicate_pad_numbers_are_jumpers no)
		(fp_line
			(start 0.7874 0.4064)
			(end -0.7874 0.4064)
			(stroke
				(width 0.1524)
				(type default)
			)
			(layer "F.SilkS")
		)
		(fp_line
			(start 0.7874 -0.4064)
			(end 0.7874 0.4064)
			(stroke
				(width 0.1524)
				(type default)
			)
			(layer "F.SilkS")
		)
		(fp_line
			(start -0.7874 0.4064)
			(end -0.7874 -0.4064)
			(stroke
				(width 0.1524)
				(type default)
			)
			(layer "F.SilkS")
		)
		(fp_line
			(start -0.7874 -0.4064)
			(end 0.7874 -0.4064)
			(stroke
				(width 0.1524)
				(type default)
			)
			(layer "F.SilkS")
		)
		(fp_line
			(start 0.67945 0.3048)
			(end 0.120396 0.3048)
			(stroke
				(width 0.1)
				(type default)
			)
			(layer "F.Fab")
		)
		(fp_line
			(start 0.67945 -0.3048)
			(end 0.67945 0.3048)
			(stroke
				(width 0.1)
				(type default)
			)
			(layer "F.Fab")
		)
		(fp_line
			(start 0.12065 -0.2794)
			(end 0.12065 -0.3048)
			(stroke
				(width 0.1)
				(type default)
			)
			(layer "F.Fab")
		)
		(fp_line
			(start 0.12065 -0.3048)
			(end 0.67945 -0.3048)
			(stroke
				(width 0.1)
				(type default)
			)
			(layer "F.Fab")
		)
		(fp_line
			(start 0.120396 0.3048)
			(end 0.120396 0.2794)
			(stroke
				(width 0.1)
				(type default)
			)
			(layer "F.Fab")
		)
		(fp_line
			(start 0.120396 0.2794)
			(end -0.12065 0.2794)
			(stroke
				(width 0.1)
				(type default)
			)
			(layer "F.Fab")
		)
		(fp_line
			(start -0.12065 0.3048)
			(end -0.67945 0.3048)
			(stroke
				(width 0.1)
				(type default)
			)
			(layer "F.Fab")
		)
		(fp_line
			(start -0.12065 0.2794)
			(end -0.12065 0.3048)
			(stroke
				(width 0.1)
				(type default)
			)
			(layer "F.Fab")
		)
		(fp_line
			(start -0.12065 -0.2794)
			(end 0.12065 -0.2794)
			(stroke
				(width 0.1)
				(type default)
			)
			(layer "F.Fab")
		)
		(fp_line
			(start -0.12065 -0.305054)
			(end -0.12065 -0.2794)
			(stroke
				(width 0.1)
				(type default)
			)
			(layer "F.Fab")
		)
		(fp_line
			(start -0.67945 0.3048)
			(end -0.67945 -0.305054)
			(stroke
				(width 0.1)
				(type default)
			)
			(layer "F.Fab")
		)
		(fp_line
			(start -0.67945 -0.305054)
			(end -0.12065 -0.305054)
			(stroke
				(width 0.1)
				(type default)
			)
			(layer "F.Fab")
		)
		(pad "1" smd circle
			(at -0.40005 0 180)
			(size 0 0)
			(layers "F.Cu" "F.Mask" "F.Paste")
			(net "FM_ESPI_FLASH_MODE")
		)
		(pad "2" smd circle
			(at 0.40005 0 180)
			(size 0 0)
			(layers "F.Cu" "F.Mask" "F.Paste")
			(net "GND")
		)
	)
	(footprint ""
		(layer "F.Cu")
		(at 404.900384 -17.612614 90)
		(property "Reference" "C849"
			(at 0 0 90)
			(layer "F.SilkS")
			(hide yes)
			(effects
				(font
					(size 1.27 1.27)
				)
			)
		)
		(property "Value" ""
			(at 0 0 90)
			(layer "F.Fab")
			(effects
				(font
					(size 1.27 1.27)
				)
			)
		)
		(duplicate_pad_numbers_are_jumpers no)
		(fp_line
			(start 0.299974 -0.150114)
			(end 0.299974 0.150114)
			(stroke
				(width 0.1)
				(type default)
			)
			(layer "F.Fab")
		)
		(fp_line
			(start -0.299974 -0.150114)
			(end 0.299974 -0.150114)
			(stroke
				(width 0.1)
				(type default)
			)
			(layer "F.Fab")
		)
		(fp_line
			(start 0.299974 0.150114)
			(end -0.299974 0.150114)
			(stroke
				(width 0.1)
				(type default)
			)
			(layer "F.Fab")
		)
		(fp_line
			(start -0.299974 0.150114)
			(end -0.299974 -0.150114)
			(stroke
				(width 0.1)
				(type default)
			)
			(layer "F.Fab")
		)
		(pad "1" smd rect
			(at -0.2667 0 90)
			(size 0.3048 0.381)
			(layers "F.Cu" "F.Mask" "F.Paste")
			(net "P5E_CPU0_PE1_TX_C_DP<10>")
		)
		(pad "2" smd rect
			(at 0.2667 0 90)
			(size 0.3048 0.381)
			(layers "F.Cu" "F.Mask" "F.Paste")
			(net "P5E_CPU0_PE1_TX_DP<10>")
		)
	)
	(footprint ""
		(layer "F.Cu")
		(at 213.4108 -107.4166 -90)
		(property "Reference" "R4777"
			(at 0 0 270)
			(layer "F.SilkS")
			(hide yes)
			(effects
				(font
					(size 1.27 1.27)
				)
			)
		)
		(property "Value" ""
			(at 0 0 270)
			(layer "F.Fab")
			(effects
				(font
					(size 1.27 1.27)
				)
			)
		)
		(duplicate_pad_numbers_are_jumpers no)
		(fp_line
			(start -0.7874 0.4064)
			(end -0.7874 -0.4064)
			(stroke
				(width 0.1524)
				(type default)
			)
			(layer "F.SilkS")
		)
		(fp_line
			(start 0.7874 0.4064)
			(end -0.7874 0.4064)
			(stroke
				(width 0.1524)
				(type default)
			)
			(layer "F.SilkS")
		)
		(fp_line
			(start -0.7874 -0.4064)
			(end 0.7874 -0.4064)
			(stroke
				(width 0.1524)
				(type default)
			)
			(layer "F.SilkS")
		)
		(fp_line
			(start 0.7874 -0.4064)
			(end 0.7874 0.4064)
			(stroke
				(width 0.1524)
				(type default)
			)
			(layer "F.SilkS")
		)
		(fp_line
			(start -0.67945 0.3048)
			(end -0.67945 -0.305054)
			(stroke
				(width 0.1)
				(type default)
			)
			(layer "F.Fab")
		)
		(fp_line
			(start -0.12065 0.3048)
			(end -0.67945 0.3048)
			(stroke
				(width 0.1)
				(type default)
			)
			(layer "F.Fab")
		)
		(fp_line
			(start 0.120396 0.3048)
			(end 0.120396 0.2794)
			(stroke
				(width 0.1)
				(type default)
			)
			(layer "F.Fab")
		)
		(fp_line
			(start 0.67945 0.3048)
			(end 0.120396 0.3048)
			(stroke
				(width 0.1)
				(type default)
			)
			(layer "F.Fab")
		)
		(fp_line
			(start -0.12065 0.2794)
			(end -0.12065 0.3048)
			(stroke
				(width 0.1)
				(type default)
			)
			(layer "F.Fab")
		)
		(fp_line
			(start 0.120396 0.2794)
			(end -0.12065 0.2794)
			(stroke
				(width 0.1)
				(type default)
			)
			(layer "F.Fab")
		)
		(fp_line
			(start -0.12065 -0.2794)
			(end 0.12065 -0.2794)
			(stroke
				(width 0.1)
				(type default)
			)
			(layer "F.Fab")
		)
		(fp_line
			(start 0.12065 -0.2794)
			(end 0.12065 -0.3048)
			(stroke
				(width 0.1)
				(type default)
			)
			(layer "F.Fab")
		)
		(fp_line
			(start 0.12065 -0.3048)
			(end 0.67945 -0.3048)
			(stroke
				(width 0.1)
				(type default)
			)
			(layer "F.Fab")
		)
		(fp_line
			(start 0.67945 -0.3048)
			(end 0.67945 0.3048)
			(stroke
				(width 0.1)
				(type default)
			)
			(layer "F.Fab")
		)
		(fp_line
			(start -0.67945 -0.305054)
			(end -0.12065 -0.305054)
			(stroke
				(width 0.1)
				(type default)
			)
			(layer "F.Fab")
		)
		(fp_line
			(start -0.12065 -0.305054)
			(end -0.12065 -0.2794)
			(stroke
				(width 0.1)
				(type default)
			)
			(layer "F.Fab")
		)
		(pad "1" smd circle
			(at -0.40005 0 270)
			(size 0 0)
			(layers "F.Cu" "F.Mask" "F.Paste")
			(net "P12V_AUX_UV_TRIGGER")
		)
		(pad "2" smd circle
			(at 0.40005 0 270)
			(size 0 0)
			(layers "F.Cu" "F.Mask" "F.Paste")
			(net "GND")
		)
	)
)
